(kicad_pcb
	(version 20260206)
	(generator "pcbnew")
	(generator_version "10.0")
	(general
		(thickness 1.6)
		(legacy_teardrops no)
	)
	(paper "A4")
	(title_block
		(title "pdpb — Lightning_PDPB_BRD.brd")
		(comment 1 "Lightning (Wiwynn / Facebook NVMe JBOF) / footprints 585-590 of 1140")
	)
	(layers
		(0 "F.Cu" signal "TOP")
		(4 "In1.Cu" signal "L2GND")
		(6 "In2.Cu" signal "L3")
		(8 "In3.Cu" signal "L4VCC")
		(10 "In4.Cu" signal "L5VCC")
		(12 "In5.Cu" signal "L6")
		(14 "In6.Cu" signal "L7GND")
		(2 "B.Cu" signal "BOTTOM")
		(9 "F.Adhes" user "F.Adhesive")
		(11 "B.Adhes" user "B.Adhesive")
		(13 "F.Paste" user "Package Geometry/Pastemask Top")
		(15 "B.Paste" user "Package Geometry/Pastemask Bottom")
		(5 "F.SilkS" user "Ref Des/Silkscreen Top")
		(7 "B.SilkS" user "Ref Des/Silkscreen Bottom")
		(1 "F.Mask" user "Board Geometry/Soldermask Top")
		(3 "B.Mask" user "Board Geometry/Soldermask Bottom")
		(17 "Dwgs.User" user "User.Drawings")
		(19 "Cmts.User" user "User.Comments")
		(21 "Eco1.User" user "User.Eco1")
		(23 "Eco2.User" user "User.Eco2")
		(25 "Edge.Cuts" user "Board Geometry/Outline")
		(27 "Margin" user)
		(31 "F.CrtYd" user "Package Geometry/Place Bound Top")
		(29 "B.CrtYd" user "Package Geometry/Place Bound Bottom")
		(35 "F.Fab" user "Ref Des/Assembly Top")
		(33 "B.Fab" user "Ref Des/Assembly Bottom")
	)
	(footprint ""
		(layer "F.Cu")
		(at 221.0054 -198.6026 -90)
		(property "Reference" "R9798"
			(at 0 0 270)
			(layer "F.SilkS")
			(hide yes)
			(effects
				(font
					(size 1.27 1.27)
				)
			)
		)
		(property "Value" "2K2R5F-GP"
			(at 0 -8.9535 270)
			(unlocked yes)
			(layer "F.Fab")
			(hide yes)
			(effects
				(font
					(size 1.27 1.016)
					(thickness 0.1524)
				)
			)
		)
		(property "Device Type" "R805H24"
			(at 0 -10.6299 270)
			(unlocked yes)
			(layer "F.Fab")
			(hide yes)
			(effects
				(font
					(size 1.27 1.016)
					(thickness 0.1524)
				)
			)
		)
		(duplicate_pad_numbers_are_jumpers no)
		(fp_line
			(start -0.889 1.7018)
			(end 0.889 1.7018)
			(stroke
				(width 0.1524)
				(type default)
			)
			(layer "F.SilkS")
		)
		(fp_line
			(start 0.889 1.7018)
			(end 0.889 -0.508)
			(stroke
				(width 0.1524)
				(type default)
			)
			(layer "F.SilkS")
		)
		(fp_line
			(start -0.889 0.0762)
			(end -0.889 1.7018)
			(stroke
				(width 0.1524)
				(type default)
			)
			(layer "F.SilkS")
		)
		(fp_line
			(start -0.889 -1.7018)
			(end -0.889 0.2794)
			(stroke
				(width 0.1524)
				(type default)
			)
			(layer "F.SilkS")
		)
		(fp_line
			(start 0.889 -1.7018)
			(end 0.889 -0.381)
			(stroke
				(width 0.1524)
				(type default)
			)
			(layer "F.SilkS")
		)
		(fp_line
			(start 0.889 -1.7018)
			(end -0.889 -1.7018)
			(stroke
				(width 0.1524)
				(type default)
			)
			(layer "F.SilkS")
		)
		(fp_poly
			(pts
				(xy 0.9652 -1.778) (xy 0.9652 1.778) (xy -0.9652 1.778) (xy -0.9652 -1.778)
			)
			(stroke
				(width 0)
				(type default)
			)
			(fill no)
			(layer "F.CrtYd")
		)
		(fp_rect
			(start -0.9652 1.778)
			(end 0.9652 -1.778)
			(stroke
				(width 0)
				(type default)
			)
			(fill no)
			(layer "F.Fab")
		)
		(pad "1" smd rect
			(at 0 -0.9652 270)
			(size 1.397 1.143)
			(layers "F.Cu" "F.Mask" "F.Paste")
			(net "P12V_SSD3")
		)
		(pad "2" smd rect
			(at 0 0.9652 270)
			(size 1.397 1.143)
			(layers "F.Cu" "F.Mask" "F.Paste")
			(net "P12V_MOST3_GATE_D")
		)
	)
	(footprint ""
		(layer "F.Cu")
		(at 10.414 -269.875 180)
		(property "Reference" "R9038"
			(at 0 0 180)
			(layer "F.SilkS")
			(hide yes)
			(effects
				(font
					(size 1.27 1.27)
				)
			)
		)
		(property "Value" "0R2J-2-GP"
			(at 0.064008 -3.993896 180)
			(unlocked yes)
			(layer "F.Fab")
			(hide yes)
			(effects
				(font
					(size 1.016 1.016)
					(thickness 0.1524)
				)
			)
		)
		(property "Device Type" "R402H16"
			(at 0.064008 -5.517896 180)
			(unlocked yes)
			(layer "F.Fab")
			(hide yes)
			(effects
				(font
					(size 1.016 1.016)
					(thickness 0.1524)
				)
			)
		)
		(duplicate_pad_numbers_are_jumpers no)
		(fp_line
			(start 0.508 -0.9398)
			(end -0.508 -0.9398)
			(stroke
				(width 0.1524)
				(type default)
			)
			(layer "F.SilkS")
		)
		(fp_line
			(start -0.508 -0.9398)
			(end -0.508 0.9398)
			(stroke
				(width 0.1524)
				(type default)
			)
			(layer "F.SilkS")
		)
		(fp_rect
			(start -0.508 0.9398)
			(end 0.508 -0.9398)
			(stroke
				(width 0)
				(type default)
			)
			(fill no)
			(layer "F.CrtYd")
		)
		(fp_rect
			(start -0.508 0.9398)
			(end 0.508 -0.9398)
			(stroke
				(width 0)
				(type default)
			)
			(fill no)
			(layer "F.Fab")
		)
		(pad "1" smd custom
			(at 0 -0.4445 180)
			(size 0.1397 0.1397)
			(layers "F.Cu" "F.Mask" "F.Paste")
			(net "SD_LATCH_RELEASE_R")
			(options
				(clearance outline)
				(anchor circle)
			)
			(primitives
				(gr_poly
					(pts
						(arc
							(start -0.1778 -0.2794)
							(mid -0.249642 -0.249642)
							(end -0.2794 -0.1778)
						)
						(arc
							(start -0.2794 0.1778)
							(mid -0.249642 0.249642)
							(end -0.1778 0.2794)
						)
						(arc
							(start 0.1778 0.2794)
							(mid 0.249642 0.249642)
							(end 0.2794 0.1778)
						)
						(arc
							(start 0.2794 -0.1778)
							(mid 0.249642 -0.249642)
							(end 0.1778 -0.2794)
						)
					)
					(width 0)
					(fill yes)
				)
			)
		)
		(pad "2" smd custom
			(at 0 0.4445 180)
			(size 0.1397 0.1397)
			(layers "F.Cu" "F.Mask" "F.Paste")
			(net "SD_LATCH_RELEASE")
			(options
				(clearance outline)
				(anchor circle)
			)
			(primitives
				(gr_poly
					(pts
						(arc
							(start -0.1778 -0.2794)
							(mid -0.249642 -0.249642)
							(end -0.2794 -0.1778)
						)
						(arc
							(start -0.2794 0.1778)
							(mid -0.249642 0.249642)
							(end -0.1778 0.2794)
						)
						(arc
							(start 0.1778 0.2794)
							(mid 0.249642 0.249642)
							(end 0.2794 0.1778)
						)
						(arc
							(start 0.2794 -0.1778)
							(mid 0.249642 -0.249642)
							(end 0.1778 -0.2794)
						)
					)
					(width 0)
					(fill yes)
				)
			)
		)
	)
	(footprint ""
		(layer "F.Cu")
		(at 13.1064 -499.1862 -90)
		(property "Reference" "Q52"
			(at 0 0 270)
			(layer "F.SilkS")
			(hide yes)
			(effects
				(font
					(size 1.27 1.27)
				)
			)
		)
		(property "Value" "2N7002A-7-GP"
			(at 0.127 -8.9662 270)
			(unlocked yes)
			(layer "F.Fab")
			(hide yes)
			(effects
				(font
					(size 1.016 1.016)
					(thickness 0.1524)
				)
			)
		)
		(property "Device Type" "SOT23DGS2D4H48"
			(at 0.127 -10.4902 270)
			(unlocked yes)
			(layer "F.Fab")
			(hide yes)
			(effects
				(font
					(size 1.016 1.016)
					(thickness 0.1524)
				)
			)
		)
		(duplicate_pad_numbers_are_jumpers no)
		(fp_line
			(start -1.651 1.778)
			(end 1.651 1.778)
			(stroke
				(width 0.1524)
				(type default)
			)
			(layer "F.SilkS")
		)
		(fp_line
			(start 1.651 1.778)
			(end 1.651 -1.778)
			(stroke
				(width 0.1524)
				(type default)
			)
			(layer "F.SilkS")
		)
		(fp_line
			(start -1.651 -1.778)
			(end -1.651 1.778)
			(stroke
				(width 0.1524)
				(type default)
			)
			(layer "F.SilkS")
		)
		(fp_line
			(start 1.651 -1.778)
			(end -1.651 -1.778)
			(stroke
				(width 0.1524)
				(type default)
			)
			(layer "F.SilkS")
		)
		(fp_poly
			(pts
				(xy -1.778 1.8796) (xy -1.778 -1.8796) (xy 1.778 -1.8796) (xy 1.778 1.8796)
			)
			(stroke
				(width 0)
				(type default)
			)
			(fill no)
			(layer "F.CrtYd")
		)
		(fp_poly
			(pts
				(xy -1.778 1.8796) (xy -1.778 -1.8796) (xy 1.778 -1.8796) (xy 1.778 1.8796)
			)
			(stroke
				(width 0)
				(type default)
			)
			(fill no)
			(layer "F.Fab")
		)
		(pad "D" smd custom
			(at 0 -0.9525 270)
			(size 0.1905 0.1905)
			(layers "F.Cu" "F.Mask" "F.Paste")
			(net "P12V_MOST5_GATE")
			(options
				(clearance outline)
				(anchor circle)
			)
			(primitives
				(gr_poly
					(pts
						(arc
							(start -0.1778 0.5715)
							(mid -0.321484 0.511984)
							(end -0.381 0.3683)
						)
						(arc
							(start -0.381 -0.3683)
							(mid -0.321484 -0.511984)
							(end -0.1778 -0.5715)
						)
						(arc
							(start 0.1778 -0.5715)
							(mid 0.321484 -0.511984)
							(end 0.381 -0.3683)
						)
						(arc
							(start 0.381 0.3683)
							(mid 0.321484 0.511984)
							(end 0.1778 0.5715)
						)
					)
					(width 0)
					(fill yes)
				)
			)
		)
		(pad "G" smd custom
			(at -0.98425 0.9525 270)
			(size 0.1905 0.1905)
			(layers "F.Cu" "F.Mask" "F.Paste")
			(net "SSD5_PWREN_R")
			(options
				(clearance outline)
				(anchor circle)
			)
			(primitives
				(gr_poly
					(pts
						(arc
							(start -0.1778 0.5715)
							(mid -0.321484 0.511984)
							(end -0.381 0.3683)
						)
						(arc
							(start -0.381 -0.3683)
							(mid -0.321484 -0.511984)
							(end -0.1778 -0.5715)
						)
						(arc
							(start 0.1778 -0.5715)
							(mid 0.321484 -0.511984)
							(end 0.381 -0.3683)
						)
						(arc
							(start 0.381 0.3683)
							(mid 0.321484 0.511984)
							(end 0.1778 0.5715)
						)
					)
					(width 0)
					(fill yes)
				)
			)
		)
		(pad "S" smd custom
			(at 0.98425 0.9525 270)
			(size 0.1905 0.1905)
			(layers "F.Cu" "F.Mask" "F.Paste")
			(net "GND")
			(options
				(clearance outline)
				(anchor circle)
			)
			(primitives
				(gr_poly
					(pts
						(arc
							(start -0.1778 0.5715)
							(mid -0.321484 0.511984)
							(end -0.381 0.3683)
						)
						(arc
							(start -0.381 -0.3683)
							(mid -0.321484 -0.511984)
							(end -0.1778 -0.5715)
						)
						(arc
							(start 0.1778 -0.5715)
							(mid 0.321484 -0.511984)
							(end 0.381 -0.3683)
						)
						(arc
							(start 0.381 0.3683)
							(mid 0.321484 0.511984)
							(end 0.1778 0.5715)
						)
					)
					(width 0)
					(fill yes)
				)
			)
		)
	)
	(footprint ""
		(layer "F.Cu")
		(at 46.228 -242.443)
		(property "Reference" "C9525"
			(at 0 0 0)
			(layer "F.SilkS")
			(hide yes)
			(effects
				(font
					(size 1.27 1.27)
				)
			)
		)
		(property "Value" "SCD1U16V2KX-3GP"
			(at 1.1811 -2.7051 0)
			(unlocked yes)
			(layer "F.Fab")
			(hide yes)
			(effects
				(font
					(size 1.016 1.016)
					(thickness 0.1524)
				)
			)
		)
		(property "Device Type" "C402H22"
			(at 1.1811 -4.2291 0)
			(unlocked yes)
			(layer "F.Fab")
			(hide yes)
			(effects
				(font
					(size 1.016 1.016)
					(thickness 0.1524)
				)
			)
		)
		(duplicate_pad_numbers_are_jumpers no)
		(fp_rect
			(start -0.4318 0.9525)
			(end 0.4318 -0.9525)
			(stroke
				(width 0)
				(type default)
			)
			(fill no)
			(layer "F.CrtYd")
		)
		(fp_rect
			(start -0.4318 0.9525)
			(end 0.4318 -0.9525)
			(stroke
				(width 0)
				(type default)
			)
			(fill no)
			(layer "F.Fab")
		)
		(pad "1" smd custom
			(at 0 -0.4445)
			(size 0.1524 0.1524)
			(layers "F.Cu" "F.Mask" "F.Paste")
			(net "P3V3")
			(options
				(clearance outline)
				(anchor circle)
			)
			(primitives
				(gr_poly
					(pts
						(arc
							(start 0.3048 -0.2032)
							(mid 0.275042 -0.275042)
							(end 0.2032 -0.3048)
						)
						(arc
							(start -0.2032 -0.3048)
							(mid -0.275042 -0.275042)
							(end -0.3048 -0.2032)
						)
						(arc
							(start -0.3048 0.2032)
							(mid -0.275042 0.275042)
							(end -0.2032 0.3048)
						)
						(arc
							(start 0.2032 0.3048)
							(mid 0.275042 0.275042)
							(end 0.3048 0.2032)
						)
					)
					(width 0)
					(fill yes)
				)
			)
		)
		(pad "2" smd custom
			(at 0 0.4445)
			(size 0.1524 0.1524)
			(layers "F.Cu" "F.Mask" "F.Paste")
			(net "GND")
			(options
				(clearance outline)
				(anchor circle)
			)
			(primitives
				(gr_poly
					(pts
						(arc
							(start 0.3048 -0.2032)
							(mid 0.275042 -0.275042)
							(end 0.2032 -0.3048)
						)
						(arc
							(start -0.2032 -0.3048)
							(mid -0.275042 -0.275042)
							(end -0.3048 -0.2032)
						)
						(arc
							(start -0.3048 0.2032)
							(mid -0.275042 0.275042)
							(end -0.2032 0.3048)
						)
						(arc
							(start 0.2032 0.3048)
							(mid 0.275042 0.275042)
							(end 0.3048 0.2032)
						)
					)
					(width 0)
					(fill yes)
				)
			)
		)
	)
	(footprint ""
		(layer "F.Cu")
		(at 49.276 -248.539 -90)
		(property "Reference" "R9463"
			(at 0 0 270)
			(layer "F.SilkS")
			(hide yes)
			(effects
				(font
					(size 1.27 1.27)
				)
			)
		)
		(property "Value" "330R2F-GP"
			(at 0.064008 -3.993896 270)
			(unlocked yes)
			(layer "F.Fab")
			(hide yes)
			(effects
				(font
					(size 1.016 1.016)
					(thickness 0.1524)
				)
			)
		)
		(property "Device Type" "R402H16"
			(at 0.064008 -5.517896 270)
			(unlocked yes)
			(layer "F.Fab")
			(hide yes)
			(effects
				(font
					(size 1.016 1.016)
					(thickness 0.1524)
				)
			)
		)
		(duplicate_pad_numbers_are_jumpers no)
		(fp_line
			(start -0.508 -0.9398)
			(end -0.508 0.9398)
			(stroke
				(width 0.1524)
				(type default)
			)
			(layer "F.SilkS")
		)
		(fp_line
			(start 0.508 -0.9398)
			(end -0.508 -0.9398)
			(stroke
				(width 0.1524)
				(type default)
			)
			(layer "F.SilkS")
		)
		(fp_rect
			(start -0.508 0.9398)
			(end 0.508 -0.9398)
			(stroke
				(width 0)
				(type default)
			)
			(fill no)
			(layer "F.CrtYd")
		)
		(fp_rect
			(start -0.508 0.9398)
			(end 0.508 -0.9398)
			(stroke
				(width 0)
				(type default)
			)
			(fill no)
			(layer "F.Fab")
		)
		(pad "1" smd custom
			(at 0 -0.4445 270)
			(size 0.1397 0.1397)
			(layers "F.Cu" "F.Mask" "F.Paste")
			(net "P3V3")
			(options
				(clearance outline)
				(anchor circle)
			)
			(primitives
				(gr_poly
					(pts
						(arc
							(start -0.1778 -0.2794)
							(mid -0.249642 -0.249642)
							(end -0.2794 -0.1778)
						)
						(arc
							(start -0.2794 0.1778)
							(mid -0.249642 0.249642)
							(end -0.1778 0.2794)
						)
						(arc
							(start 0.1778 0.2794)
							(mid 0.249642 0.249642)
							(end 0.2794 0.1778)
						)
						(arc
							(start 0.2794 -0.1778)
							(mid 0.249642 -0.249642)
							(end 0.1778 -0.2794)
						)
					)
					(width 0)
					(fill yes)
				)
			)
		)
		(pad "2" smd custom
			(at 0 0.4445 270)
			(size 0.1397 0.1397)
			(layers "F.Cu" "F.Mask" "F.Paste")
			(net "DRV_ATTN_7")
			(options
				(clearance outline)
				(anchor circle)
			)
			(primitives
				(gr_poly
					(pts
						(arc
							(start -0.1778 -0.2794)
							(mid -0.249642 -0.249642)
							(end -0.2794 -0.1778)
						)
						(arc
							(start -0.2794 0.1778)
							(mid -0.249642 0.249642)
							(end -0.1778 0.2794)
						)
						(arc
							(start 0.1778 0.2794)
							(mid 0.249642 0.249642)
							(end 0.2794 0.1778)
						)
						(arc
							(start 0.2794 -0.1778)
							(mid 0.249642 -0.249642)
							(end 0.1778 -0.2794)
						)
					)
					(width 0)
					(fill yes)
				)
			)
		)
	)
	(footprint ""
		(layer "F.Cu")
		(at 108.966 -205.994)
		(property "Reference" "R9444"
			(at 0 0 0)
			(layer "F.SilkS")
			(hide yes)
			(effects
				(font
					(size 1.27 1.27)
				)
			)
		)
		(property "Value" "4K7R2J-2-GP"
			(at 0.064008 -3.993896 0)
			(unlocked yes)
			(layer "F.Fab")
			(hide yes)
			(effects
				(font
					(size 1.016 1.016)
					(thickness 0.1524)
				)
			)
		)
		(property "Device Type" "R402H16"
			(at 0.064008 -5.517896 0)
			(unlocked yes)
			(layer "F.Fab")
			(hide yes)
			(effects
				(font
					(size 1.016 1.016)
					(thickness 0.1524)
				)
			)
		)
		(duplicate_pad_numbers_are_jumpers no)
		(fp_line
			(start -0.508 -0.9398)
			(end -0.508 0.9398)
			(stroke
				(width 0.1524)
				(type default)
			)
			(layer "F.SilkS")
		)
		(fp_line
			(start 0.508 -0.9398)
			(end -0.508 -0.9398)
			(stroke
				(width 0.1524)
				(type default)
			)
			(layer "F.SilkS")
		)
		(fp_rect
			(start -0.508 0.9398)
			(end 0.508 -0.9398)
			(stroke
				(width 0)
				(type default)
			)
			(fill no)
			(layer "F.CrtYd")
		)
		(fp_rect
			(start -0.508 0.9398)
			(end 0.508 -0.9398)
			(stroke
				(width 0)
				(type default)
			)
			(fill no)
			(layer "F.Fab")
		)
		(pad "1" smd custom
			(at 0 -0.4445)
			(size 0.1397 0.1397)
			(layers "F.Cu" "F.Mask" "F.Paste")
			(net "P3V3")
			(options
				(clearance outline)
				(anchor circle)
			)
			(primitives
				(gr_poly
					(pts
						(arc
							(start -0.1778 -0.2794)
							(mid -0.249642 -0.249642)
							(end -0.2794 -0.1778)
						)
						(arc
							(start -0.2794 0.1778)
							(mid -0.249642 0.249642)
							(end -0.1778 0.2794)
						)
						(arc
							(start 0.1778 0.2794)
							(mid 0.249642 0.249642)
							(end 0.2794 0.1778)
						)
						(arc
							(start 0.2794 -0.1778)
							(mid 0.249642 -0.249642)
							(end 0.1778 -0.2794)
						)
					)
					(width 0)
					(fill yes)
				)
			)
		)
		(pad "2" smd custom
			(at 0 0.4445)
			(size 0.1397 0.1397)
			(layers "F.Cu" "F.Mask" "F.Paste")
			(net "SSD_PRSNT_NET3")
			(options
				(clearance outline)
				(anchor circle)
			)
			(primitives
				(gr_poly
					(pts
						(arc
							(start -0.1778 -0.2794)
							(mid -0.249642 -0.249642)
							(end -0.2794 -0.1778)
						)
						(arc
							(start -0.2794 0.1778)
							(mid -0.249642 0.249642)
							(end -0.1778 0.2794)
						)
						(arc
							(start 0.1778 0.2794)
							(mid 0.249642 0.249642)
							(end 0.2794 0.1778)
						)
						(arc
							(start 0.2794 -0.1778)
							(mid 0.249642 -0.249642)
							(end 0.1778 -0.2794)
						)
					)
					(width 0)
					(fill yes)
				)
			)
		)
	)
)
